(kicad_pcb
	(version 20241229)
	(generator "pcbnew")
	(generator_version "9.0")
	(general
		(thickness 1.599998)
		(legacy_teardrops no)
	)
	(paper "A4")
	(title_block
		(date "2023-02-12")
		(rev "1.1.5")
		(comment 9 "footprints 43-49 of 473")
	)
	(layers
		(0 "F.Cu" signal)
		(4 "In1.Cu" power "In1.GND")
		(6 "In2.Cu" signal)
		(8 "In3.Cu" power "In3.GND")
		(10 "In4.Cu" power "In4.VCC")
		(12 "In5.Cu" signal)
		(14 "In6.Cu" power "In6.VCC")
		(2 "B.Cu" signal)
		(9 "F.Adhes" user "F.Adhesive")
		(11 "B.Adhes" user "B.Adhesive")
		(13 "F.Paste" user)
		(15 "B.Paste" user)
		(5 "F.SilkS" user "F.Silkscreen")
		(7 "B.SilkS" user "B.Silkscreen")
		(1 "F.Mask" user)
		(3 "B.Mask" user)
		(17 "Dwgs.User" user "User.Drawings")
		(19 "Cmts.User" user "User.Comments")
		(21 "Eco1.User" user "User.Eco1")
		(23 "Eco2.User" user "User.Eco2")
		(25 "Edge.Cuts" user)
		(27 "Margin" user)
		(31 "F.CrtYd" user "F.Courtyard")
		(29 "B.CrtYd" user "B.Courtyard")
		(35 "F.Fab" user)
		(33 "B.Fab" user)
	)
	(footprint "antmicro-footprints:C_0402_1005Metric"
		(layer "F.Cu")
		(at 148.661328 108.781157)
		(descr "Capacitor SMD 0402")
		(tags "capacitor SMD 0402")
		(property "Reference" "C19"
			(at 0.764672 0.428843 0)
			(layer "F.SilkS")
			(effects
				(font
					(size 0.7 0.7)
					(thickness 0.15)
				)
				(justify left bottom)
			)
		)
		(property "Value" "C_100n_6V3_0402"
			(at 0 1.4 0)
			(layer "F.Fab")
			(effects
				(font
					(size 0.7 0.7)
					(thickness 0.15)
				)
				(justify left bottom)
			)
		)
		(property "Description" " "
			(at 0 0 0)
			(layer "F.Fab")
			(hide yes)
			(effects
				(font
					(size 1.27 1.27)
					(thickness 0.15)
				)
			)
		)
		(property "Author" "Antmicro"
			(at 0 0 0)
			(layer "F.Fab")
			(hide yes)
			(effects
				(font
					(size 1 1)
					(thickness 0.15)
				)
			)
		)
		(property "Dielectric" ""
			(at 0 0 0)
			(layer "F.Fab")
			(hide yes)
			(effects
				(font
					(size 1 1)
					(thickness 0.15)
				)
			)
		)
		(property "License" "Apache-2.0"
			(at 0 0 0)
			(layer "F.Fab")
			(hide yes)
			(effects
				(font
					(size 1 1)
					(thickness 0.15)
				)
			)
		)
		(property "MPN" "0402X104K6R3CT"
			(at 0 0 0)
			(layer "F.Fab")
			(hide yes)
			(effects
				(font
					(size 1 1)
					(thickness 0.15)
				)
			)
		)
		(property "Manufacturer" "Walsin"
			(at 0 0 0)
			(layer "F.Fab")
			(hide yes)
			(effects
				(font
					(size 1 1)
					(thickness 0.15)
				)
			)
		)
		(property "Val" "100n"
			(at 0 0 0)
			(layer "F.Fab")
			(hide yes)
			(effects
				(font
					(size 1 1)
					(thickness 0.15)
				)
			)
		)
		(property "Voltage" ""
			(at 0 0 0)
			(layer "F.Fab")
			(hide yes)
			(effects
				(font
					(size 1 1)
					(thickness 0.15)
				)
			)
		)
		(sheetname "Interfaces")
		(sheetfile "interfaces.kicad_sch")
		(attr smd)
		(fp_rect
			(start -0.94 -0.47)
			(end 0.94 0.47)
			(stroke
				(width 0.05)
				(type solid)
			)
			(fill no)
			(layer "F.CrtYd")
		)
		(fp_rect
			(start -0.499 -0.249)
			(end 0.499 0.249)
			(stroke
				(width 0.15)
				(type solid)
			)
			(fill no)
			(layer "F.Fab")
		)
		(pad "1" smd roundrect
			(at -0.484 0)
			(size 0.59 0.64)
			(layers "F.Cu" "F.Mask" "F.Paste")
			(roundrect_rratio 0.25)
			(net 459 "3V3_SYS")
			(pintype "passive")
		)
		(pad "2" smd roundrect
			(at 0.484 0)
			(size 0.59 0.64)
			(layers "F.Cu" "F.Mask" "F.Paste")
			(roundrect_rratio 0.25)
			(net 5 "GND")
			(pintype "passive")
		)
	)
	(footprint "antmicro-footprints:C_0402_1005Metric"
		(layer "F.Cu")
		(at 143.165 102.174 -90)
		(descr "Capacitor SMD 0402")
		(tags "capacitor SMD 0402")
		(property "Reference" "C10"
			(at 1.126 0.465 270)
			(layer "F.SilkS")
			(effects
				(font
					(size 0.7 0.7)
					(thickness 0.15)
				)
				(justify left bottom)
			)
		)
		(property "Value" "C_4u7_0402"
			(at 0 1.4 270)
			(layer "F.Fab")
			(effects
				(font
					(size 0.7 0.7)
					(thickness 0.15)
				)
				(justify left bottom)
			)
		)
		(property "Description" " "
			(at 0 0 270)
			(layer "F.Fab")
			(hide yes)
			(effects
				(font
					(size 1.27 1.27)
					(thickness 0.15)
				)
			)
		)
		(property "Author" "Antmicro"
			(at 40.991 245.339 0)
			(layer "F.Fab")
			(hide yes)
			(effects
				(font
					(size 1 1)
					(thickness 0.15)
				)
			)
		)
		(property "Dielectric" ""
			(at 40.991 245.339 0)
			(layer "F.Fab")
			(hide yes)
			(effects
				(font
					(size 1 1)
					(thickness 0.15)
				)
			)
		)
		(property "License" "Apache-2.0"
			(at 40.991 245.339 0)
			(layer "F.Fab")
			(hide yes)
			(effects
				(font
					(size 1 1)
					(thickness 0.15)
				)
			)
		)
		(property "MPN" "GRM155R61A475MEAAD"
			(at 40.991 245.339 0)
			(layer "F.Fab")
			(hide yes)
			(effects
				(font
					(size 1 1)
					(thickness 0.15)
				)
			)
		)
		(property "Manufacturer" "Murata"
			(at 40.991 245.339 0)
			(layer "F.Fab")
			(hide yes)
			(effects
				(font
					(size 1 1)
					(thickness 0.15)
				)
			)
		)
		(property "Val" "4u7"
			(at 40.991 245.339 0)
			(layer "F.Fab")
			(hide yes)
			(effects
				(font
					(size 1 1)
					(thickness 0.15)
				)
			)
		)
		(property "Voltage" ""
			(at 40.991 245.339 0)
			(layer "F.Fab")
			(hide yes)
			(effects
				(font
					(size 1 1)
					(thickness 0.15)
				)
			)
		)
		(sheetname "Interfaces")
		(sheetfile "interfaces.kicad_sch")
		(attr smd)
		(fp_rect
			(start -0.94 -0.47)
			(end 0.94 0.47)
			(stroke
				(width 0.05)
				(type solid)
			)
			(fill no)
			(layer "F.CrtYd")
		)
		(fp_rect
			(start -0.499 -0.249)
			(end 0.499 0.249)
			(stroke
				(width 0.15)
				(type solid)
			)
			(fill no)
			(layer "F.Fab")
		)
		(pad "1" smd roundrect
			(at -0.484 0 270)
			(size 0.59 0.64)
			(layers "F.Cu" "F.Mask" "F.Paste")
			(roundrect_rratio 0.25)
			(net 5 "GND")
			(pintype "passive")
		)
		(pad "2" smd roundrect
			(at 0.484 0 270)
			(size 0.59 0.64)
			(layers "F.Cu" "F.Mask" "F.Paste")
			(roundrect_rratio 0.25)
			(net 2 "/Interfaces/1V8_FT")
			(pintype "passive")
		)
	)
	(footprint "antmicro-footprints:FB_0603_1608Metric"
		(layer "F.Cu")
		(at 138.786328 117.496157 90)
		(property "Reference" "FB2"
			(at -1.103843 1.513672 90)
			(layer "F.SilkS")
			(effects
				(font
					(size 0.7 0.7)
					(thickness 0.15)
				)
				(justify left bottom)
			)
		)
		(property "Value" "FB_600Z_0.5A_0603"
			(at 0 1.5 90)
			(layer "F.Fab")
			(effects
				(font
					(size 0.7 0.7)
					(thickness 0.15)
				)
				(justify left bottom)
			)
		)
		(property "Description" "Ferrite Beads WE-TMSB Suppression 240Ohm 200mA "
			(at 0 0 90)
			(layer "F.Fab")
			(hide yes)
			(effects
				(font
					(size 1.27 1.27)
					(thickness 0.15)
				)
			)
		)
		(property "Author" "Antmicro"
			(at 256.282485 -21.290171 0)
			(layer "F.Fab")
			(hide yes)
			(effects
				(font
					(size 1 1)
					(thickness 0.15)
				)
			)
		)
		(property "License" "Apache-2.0"
			(at 256.282485 -21.290171 0)
			(layer "F.Fab")
			(hide yes)
			(effects
				(font
					(size 1 1)
					(thickness 0.15)
				)
			)
		)
		(property "MPN" "BLM18AG601SN1D"
			(at 256.282485 -21.290171 0)
			(layer "F.Fab")
			(hide yes)
			(effects
				(font
					(size 1 1)
					(thickness 0.15)
				)
			)
		)
		(property "Manufacturer" "Murata"
			(at 256.282485 -21.290171 0)
			(layer "F.Fab")
			(hide yes)
			(effects
				(font
					(size 1 1)
					(thickness 0.15)
				)
			)
		)
		(sheetname "Interfaces")
		(sheetfile "interfaces.kicad_sch")
		(attr smd)
		(fp_line
			(start -0.196 -0.408)
			(end 0.193 -0.408)
			(stroke
				(width 0.15)
				(type solid)
			)
			(layer "F.SilkS")
		)
		(fp_line
			(start -0.196 0.406)
			(end 0.193 0.406)
			(stroke
				(width 0.15)
				(type solid)
			)
			(layer "F.SilkS")
		)
		(fp_rect
			(start -1.3 -0.6)
			(end 1.3 0.6)
			(stroke
				(width 0.05)
				(type solid)
			)
			(fill no)
			(layer "F.CrtYd")
		)
		(fp_line
			(start 0.8 -0.408)
			(end -0.803 -0.408)
			(stroke
				(width 0.15)
				(type solid)
			)
			(layer "F.Fab")
		)
		(fp_line
			(start 0.8 -0.408)
			(end 0.8 0.406)
			(stroke
				(width 0.15)
				(type solid)
			)
			(layer "F.Fab")
		)
		(fp_line
			(start 0.8 0.406)
			(end -0.803 0.406)
			(stroke
				(width 0.15)
				(type solid)
			)
			(layer "F.Fab")
		)
		(fp_line
			(start -0.803 0.406)
			(end -0.803 -0.408)
			(stroke
				(width 0.15)
				(type solid)
			)
			(layer "F.Fab")
		)
		(pad "1" smd roundrect
			(at -0.891 0 90)
			(size 0.762 1.09)
			(layers "F.Cu" "F.Mask" "F.Paste")
			(roundrect_rratio 0.15)
			(net 459 "3V3_SYS")
			(pintype "passive")
		)
		(pad "2" smd roundrect
			(at 0.888 0 90)
			(size 0.762 1.09)
			(layers "F.Cu" "F.Mask" "F.Paste")
			(roundrect_rratio 0.15)
			(net 653 "/Interfaces/VPHY")
			(pintype "passive")
		)
	)
	(footprint "antmicro-footprints:R_0402_1005Metric"
		(layer "F.Cu")
		(at 139.776328 114.626157 -90)
		(descr "Resistor SMD 0402")
		(tags "resistor SMD 0402")
		(property "Reference" "R7"
			(at 0.773843 -1.223672 270)
			(layer "F.SilkS")
			(effects
				(font
					(size 0.7 0.7)
					(thickness 0.15)
				)
				(justify left bottom)
			)
		)
		(property "Value" "R_12k_0402"
			(at 0 1.4 270)
			(layer "F.Fab")
			(effects
				(font
					(size 0.7 0.7)
					(thickness 0.15)
				)
				(justify left bottom)
			)
		)
		(property "Description" "12k resistor in 0402 package with 1% tolerance"
			(at 0 0 270)
			(layer "F.Fab")
			(hide yes)
			(effects
				(font
					(size 1.27 1.27)
					(thickness 0.15)
				)
			)
		)
		(property "Author" "Antmicro"
			(at 25.150171 254.402485 0)
			(layer "F.Fab")
			(hide yes)
			(effects
				(font
					(size 1 1)
					(thickness 0.15)
				)
			)
		)
		(property "License" "Apache-2.0"
			(at 25.150171 254.402485 0)
			(layer "F.Fab")
			(hide yes)
			(effects
				(font
					(size 1 1)
					(thickness 0.15)
				)
			)
		)
		(property "MPN" "CR0402-FX-1202GLF"
			(at 25.150171 254.402485 0)
			(layer "F.Fab")
			(hide yes)
			(effects
				(font
					(size 1 1)
					(thickness 0.15)
				)
			)
		)
		(property "Manufacturer" "Bourns"
			(at 25.150171 254.402485 0)
			(layer "F.Fab")
			(hide yes)
			(effects
				(font
					(size 1 1)
					(thickness 0.15)
				)
			)
		)
		(property "Tolerance" "1%"
			(at 25.150171 254.402485 0)
			(layer "F.Fab")
			(hide yes)
			(effects
				(font
					(size 1 1)
					(thickness 0.15)
				)
			)
		)
		(property "Val" "12k"
			(at 25.150171 254.402485 0)
			(layer "F.Fab")
			(hide yes)
			(effects
				(font
					(size 1 1)
					(thickness 0.15)
				)
			)
		)
		(sheetname "Interfaces")
		(sheetfile "interfaces.kicad_sch")
		(attr smd)
		(fp_rect
			(start -0.93 -0.47)
			(end 0.93 0.47)
			(stroke
				(width 0.05)
				(type solid)
			)
			(fill no)
			(layer "F.CrtYd")
		)
		(fp_rect
			(start -0.5 -0.25)
			(end 0.5 0.25)
			(stroke
				(width 0.15)
				(type solid)
			)
			(fill no)
			(layer "F.Fab")
		)
		(pad "1" smd roundrect
			(at -0.485 0 270)
			(size 0.59 0.64)
			(layers "F.Cu" "F.Mask" "F.Paste")
			(roundrect_rratio 0.25)
			(net 239 "Net-(U4-REF)")
			(pintype "passive")
		)
		(pad "2" smd roundrect
			(at 0.485 0 270)
			(size 0.59 0.64)
			(layers "F.Cu" "F.Mask" "F.Paste")
			(roundrect_rratio 0.25)
			(net 5 "GND")
			(pintype "passive")
		)
	)
	(footprint "antmicro-footprints:C_0402_1005Metric"
		(layer "F.Cu")
		(at 142.066328 115.236157 180)
		(descr "Capacitor SMD 0402")
		(tags "capacitor SMD 0402")
		(property "Reference" "C8"
			(at -0.733672 -0.363843 180)
			(layer "F.SilkS")
			(effects
				(font
					(size 0.7 0.7)
					(thickness 0.15)
				)
				(justify left bottom)
			)
		)
		(property "Value" "C_100n_6V3_0402"
			(at 0 1.4 180)
			(layer "F.Fab")
			(effects
				(font
					(size 0.7 0.7)
					(thickness 0.15)
				)
				(justify left bottom)
			)
		)
		(property "Description" " "
			(at 0 0 180)
			(layer "F.Fab")
			(hide yes)
			(effects
				(font
					(size 1.27 1.27)
					(thickness 0.15)
				)
			)
		)
		(property "Author" "Antmicro"
			(at 284.132656 230.472314 0)
			(layer "F.Fab")
			(hide yes)
			(effects
				(font
					(size 1 1)
					(thickness 0.15)
				)
			)
		)
		(property "Dielectric" ""
			(at 284.132656 230.472314 0)
			(layer "F.Fab")
			(hide yes)
			(effects
				(font
					(size 1 1)
					(thickness 0.15)
				)
			)
		)
		(property "License" "Apache-2.0"
			(at 284.132656 230.472314 0)
			(layer "F.Fab")
			(hide yes)
			(effects
				(font
					(size 1 1)
					(thickness 0.15)
				)
			)
		)
		(property "MPN" "0402X104K6R3CT"
			(at 284.132656 230.472314 0)
			(layer "F.Fab")
			(hide yes)
			(effects
				(font
					(size 1 1)
					(thickness 0.15)
				)
			)
		)
		(property "Manufacturer" "Walsin"
			(at 284.132656 230.472314 0)
			(layer "F.Fab")
			(hide yes)
			(effects
				(font
					(size 1 1)
					(thickness 0.15)
				)
			)
		)
		(property "Val" "100n"
			(at 284.132656 230.472314 0)
			(layer "F.Fab")
			(hide yes)
			(effects
				(font
					(size 1 1)
					(thickness 0.15)
				)
			)
		)
		(property "Voltage" ""
			(at 284.132656 230.472314 0)
			(layer "F.Fab")
			(hide yes)
			(effects
				(font
					(size 1 1)
					(thickness 0.15)
				)
			)
		)
		(sheetname "Interfaces")
		(sheetfile "interfaces.kicad_sch")
		(attr smd)
		(fp_rect
			(start -0.94 -0.47)
			(end 0.94 0.47)
			(stroke
				(width 0.05)
				(type solid)
			)
			(fill no)
			(layer "F.CrtYd")
		)
		(fp_rect
			(start -0.499 -0.249)
			(end 0.499 0.249)
			(stroke
				(width 0.15)
				(type solid)
			)
			(fill no)
			(layer "F.Fab")
		)
		(pad "1" smd roundrect
			(at -0.484 0 180)
			(size 0.59 0.64)
			(layers "F.Cu" "F.Mask" "F.Paste")
			(roundrect_rratio 0.25)
			(net 5 "GND")
			(pintype "passive")
		)
		(pad "2" smd roundrect
			(at 0.484 0 180)
			(size 0.59 0.64)
			(layers "F.Cu" "F.Mask" "F.Paste")
			(roundrect_rratio 0.25)
			(net 652 "/Interfaces/VPLL")
			(pintype "passive")
		)
	)
	(footprint "antmicro-footprints:C_0402_1005Metric"
		(layer "F.Cu")
		(at 142.066328 114.156157 180)
		(descr "Capacitor SMD 0402")
		(tags "capacitor SMD 0402")
		(property "Reference" "C14"
			(at 1.066328 0.456157 180)
			(layer "F.SilkS")
			(effects
				(font
					(size 0.7 0.7)
					(thickness 0.15)
				)
				(justify left bottom)
			)
		)
		(property "Value" "C_4u7_0402"
			(at 0 1.4 180)
			(layer "F.Fab")
			(effects
				(font
					(size 0.7 0.7)
					(thickness 0.15)
				)
				(justify left bottom)
			)
		)
		(property "Description" " "
			(at 0 0 180)
			(layer "F.Fab")
			(hide yes)
			(effects
				(font
					(size 1.27 1.27)
					(thickness 0.15)
				)
			)
		)
		(property "Author" "Antmicro"
			(at 284.132656 228.312314 0)
			(layer "F.Fab")
			(hide yes)
			(effects
				(font
					(size 1 1)
					(thickness 0.15)
				)
			)
		)
		(property "Dielectric" ""
			(at 284.132656 228.312314 0)
			(layer "F.Fab")
			(hide yes)
			(effects
				(font
					(size 1 1)
					(thickness 0.15)
				)
			)
		)
		(property "License" "Apache-2.0"
			(at 284.132656 228.312314 0)
			(layer "F.Fab")
			(hide yes)
			(effects
				(font
					(size 1 1)
					(thickness 0.15)
				)
			)
		)
		(property "MPN" "GRM155R61A475MEAAD"
			(at 284.132656 228.312314 0)
			(layer "F.Fab")
			(hide yes)
			(effects
				(font
					(size 1 1)
					(thickness 0.15)
				)
			)
		)
		(property "Manufacturer" "Murata"
			(at 284.132656 228.312314 0)
			(layer "F.Fab")
			(hide yes)
			(effects
				(font
					(size 1 1)
					(thickness 0.15)
				)
			)
		)
		(property "Val" "4u7"
			(at 284.132656 228.312314 0)
			(layer "F.Fab")
			(hide yes)
			(effects
				(font
					(size 1 1)
					(thickness 0.15)
				)
			)
		)
		(property "Voltage" ""
			(at 284.132656 228.312314 0)
			(layer "F.Fab")
			(hide yes)
			(effects
				(font
					(size 1 1)
					(thickness 0.15)
				)
			)
		)
		(sheetname "Interfaces")
		(sheetfile "interfaces.kicad_sch")
		(attr smd)
		(fp_rect
			(start -0.94 -0.47)
			(end 0.94 0.47)
			(stroke
				(width 0.05)
				(type solid)
			)
			(fill no)
			(layer "F.CrtYd")
		)
		(fp_rect
			(start -0.499 -0.249)
			(end 0.499 0.249)
			(stroke
				(width 0.15)
				(type solid)
			)
			(fill no)
			(layer "F.Fab")
		)
		(pad "1" smd roundrect
			(at -0.484 0 180)
			(size 0.59 0.64)
			(layers "F.Cu" "F.Mask" "F.Paste")
			(roundrect_rratio 0.25)
			(net 5 "GND")
			(pintype "passive")
		)
		(pad "2" smd roundrect
			(at 0.484 0 180)
			(size 0.59 0.64)
			(layers "F.Cu" "F.Mask" "F.Paste")
			(roundrect_rratio 0.25)
			(net 652 "/Interfaces/VPLL")
			(pintype "passive")
		)
	)
	(footprint "antmicro-footprints:R_0402_1005Metric"
		(layer "F.Cu")
		(at 176.169 130.082 -90)
		(descr "Resistor SMD 0402")
		(tags "resistor SMD 0402")
		(property "Reference" "R34"
			(at -0.782 -0.431 270)
			(layer "F.SilkS")
			(effects
				(font
					(size 0.7 0.7)
					(thickness 0.15)
				)
				(justify left bottom)
			)
		)
		(property "Value" "R_20k_0402"
			(at 0 1.4 270)
			(layer "F.Fab")
			(effects
				(font
					(size 0.7 0.7)
					(thickness 0.15)
				)
				(justify left bottom)
			)
		)
		(property "Description" "20k resistor in 0402 package with 1% tolerance"
			(at 0 0 270)
			(layer "F.Fab")
			(hide yes)
			(effects
				(font
					(size 1.27 1.27)
					(thickness 0.15)
				)
			)
		)
		(property "Author" "Antmicro"
			(at 46.087 306.251 0)
			(layer "F.Fab")
			(hide yes)
			(effects
				(font
					(size 1 1)
					(thickness 0.15)
				)
			)
		)
		(property "License" "Apache-2.0"
			(at 46.087 306.251 0)
			(layer "F.Fab")
			(hide yes)
			(effects
				(font
					(size 1 1)
					(thickness 0.15)
				)
			)
		)
		(property "MPN" "CR0402-FX-2002GLF"
			(at 46.087 306.251 0)
			(layer "F.Fab")
			(hide yes)
			(effects
				(font
					(size 1 1)
					(thickness 0.15)
				)
			)
		)
		(property "Manufacturer" "Bourns"
			(at 46.087 306.251 0)
			(layer "F.Fab")
			(hide yes)
			(effects
				(font
					(size 1 1)
					(thickness 0.15)
				)
			)
		)
		(property "Tolerance" "1%"
			(at 46.087 306.251 0)
			(layer "F.Fab")
			(hide yes)
			(effects
				(font
					(size 1 1)
					(thickness 0.15)
				)
			)
		)
		(property "Val" "20k"
			(at 46.087 306.251 0)
			(layer "F.Fab")
			(hide yes)
			(effects
				(font
					(size 1 1)
					(thickness 0.15)
				)
			)
		)
		(sheetname "Interfaces")
		(sheetfile "interfaces.kicad_sch")
		(attr smd)
		(fp_rect
			(start -0.93 -0.47)
			(end 0.93 0.47)
			(stroke
				(width 0.05)
				(type solid)
			)
			(fill no)
			(layer "F.CrtYd")
		)
		(fp_rect
			(start -0.5 -0.25)
			(end 0.5 0.25)
			(stroke
				(width 0.15)
				(type solid)
			)
			(fill no)
			(layer "F.Fab")
		)
		(pad "1" smd roundrect
			(at -0.485 0 270)
			(size 0.59 0.64)
			(layers "F.Cu" "F.Mask" "F.Paste")
			(roundrect_rratio 0.25)
			(net 459 "3V3_SYS")
			(pintype "passive")
		)
		(pad "2" smd roundrect
			(at 0.485 0 270)
			(size 0.59 0.64)
			(layers "F.Cu" "F.Mask" "F.Paste")
			(roundrect_rratio 0.25)
			(net 194 "SD_CLK")
			(pintype "passive")
		)
	)
)
